# S9S_MB_2U (Grand Teton) — schematic netlist excerpt (pin names and nets, part order shuffled) for the footprints in the layout excerpt that follows; sources: Cadence DE-HDL packaged netlist, KiCad conversion of 03242023_DA0F0TMBIJ0_F0T_Motherboard_J_brd_V01_OCP.brd

R2419  Q_RES  33.2 1% CHIP  pkg 0402LF  page 240 : A = SMB_HOST_3V3AUX_SCL ; B = SMB_HOST_3V3AUX_SCL_R0
R337  Q_RES  0 5% CHIP  pkg 0402LF  page 225 : A = H_CPU1_ERR0_LVC1_R_N ; B = H_CPU_ERR0_LVC1_R_N

(kicad_pcb
	(version 20260206)
	(generator "pcbnew")
	(generator_version "10.0")
	(general
		(thickness 1.6)
		(legacy_teardrops no)
	)
	(paper "A4")
	(title_block
		(title "03242023_DA0F0TMBIJ0_F0T_Motherboard_J_brd_V01_OCP.brd")
		(comment 1 "Grand Teton / footprints 4925-4926 of 6105")
	)
	(layers
		(0 "F.Cu" signal "TOP")
		(4 "In1.Cu" signal "GND")
		(6 "In2.Cu" signal "IN1")
		(8 "In3.Cu" signal "GND1")
		(10 "In4.Cu" signal "IN2")
		(12 "In5.Cu" signal "GND2")
		(14 "In6.Cu" signal "IN3")
		(16 "In7.Cu" signal "GND3")
		(18 "In8.Cu" signal "VCC")
		(20 "In9.Cu" signal "VCC1")
		(22 "In10.Cu" signal "GND4")
		(24 "In11.Cu" signal "IN4")
		(26 "In12.Cu" signal "GND5")
		(28 "In13.Cu" signal "IN5")
		(30 "In14.Cu" signal "GND6")
		(32 "In15.Cu" signal "IN6")
		(34 "In16.Cu" signal "GND7")
		(2 "B.Cu" signal "BOTTOM")
		(9 "F.Adhes" user "F.Adhesive")
		(11 "B.Adhes" user "B.Adhesive")
		(13 "F.Paste" user "Package Geometry/Pastemask Top")
		(15 "B.Paste" user "Package Geometry/Pastemask Bottom")
		(5 "F.SilkS" user "Ref Des/Silkscreen Top")
		(7 "B.SilkS" user "Ref Des/Silkscreen Bottom")
		(1 "F.Mask" user "Board Geometry/Soldermask Top")
		(3 "B.Mask" user "Board Geometry/Soldermask Bottom")
		(17 "Dwgs.User" user "User.Drawings")
		(19 "Cmts.User" user "User.Comments")
		(21 "Eco1.User" user "User.Eco1")
		(23 "Eco2.User" user "User.Eco2")
		(25 "Edge.Cuts" user "Board Geometry/Outline")
		(27 "Margin" user)
		(31 "F.CrtYd" user "Package Geometry/Place Bound Top")
		(29 "B.CrtYd" user "Package Geometry/Place Bound Bottom")
		(35 "F.Fab" user "Ref Des/Assembly Top")
		(33 "B.Fab" user "Ref Des/Assembly Bottom")
	)
	(footprint ""
		(layer "B.Cu")
		(at 181.86146 -18.710148 90)
		(property "Reference" "R2419"
			(at 0 0 90)
			(layer "B.SilkS")
			(hide yes)
			(effects
				(font
					(size 1.27 1.27)
				)
				(justify mirror)
			)
		)
		(property "Value" ""
			(at 0 0 90)
			(layer "B.Fab")
			(effects
				(font
					(size 1.27 1.27)
				)
				(justify mirror)
			)
		)
		(duplicate_pad_numbers_are_jumpers no)
		(fp_line
			(start 0.7874 -0.4064)
			(end -0.7874 -0.4064)
			(stroke
				(width 0.1524)
				(type default)
			)
			(layer "B.SilkS")
		)
		(fp_line
			(start -0.7874 -0.4064)
			(end -0.7874 0.4064)
			(stroke
				(width 0.1524)
				(type default)
			)
			(layer "B.SilkS")
		)
		(fp_line
			(start 0.7874 0.4064)
			(end 0.7874 -0.4064)
			(stroke
				(width 0.1524)
				(type default)
			)
			(layer "B.SilkS")
		)
		(fp_line
			(start -0.7874 0.4064)
			(end 0.7874 0.4064)
			(stroke
				(width 0.1524)
				(type default)
			)
			(layer "B.SilkS")
		)
		(fp_line
			(start 0.67945 -0.305054)
			(end 0.12065 -0.305054)
			(stroke
				(width 0.1)
				(type default)
			)
			(layer "B.Fab")
		)
		(fp_line
			(start 0.12065 -0.305054)
			(end 0.12065 -0.2794)
			(stroke
				(width 0.1)
				(type default)
			)
			(layer "B.Fab")
		)
		(fp_line
			(start -0.12065 -0.3048)
			(end -0.67945 -0.3048)
			(stroke
				(width 0.1)
				(type default)
			)
			(layer "B.Fab")
		)
		(fp_line
			(start -0.67945 -0.3048)
			(end -0.67945 0.3048)
			(stroke
				(width 0.1)
				(type default)
			)
			(layer "B.Fab")
		)
		(fp_line
			(start 0.12065 -0.2794)
			(end -0.12065 -0.2794)
			(stroke
				(width 0.1)
				(type default)
			)
			(layer "B.Fab")
		)
		(fp_line
			(start -0.12065 -0.2794)
			(end -0.12065 -0.3048)
			(stroke
				(width 0.1)
				(type default)
			)
			(layer "B.Fab")
		)
		(fp_line
			(start 0.12065 0.2794)
			(end 0.12065 0.3048)
			(stroke
				(width 0.1)
				(type default)
			)
			(layer "B.Fab")
		)
		(fp_line
			(start -0.120396 0.2794)
			(end 0.12065 0.2794)
			(stroke
				(width 0.1)
				(type default)
			)
			(layer "B.Fab")
		)
		(fp_line
			(start 0.67945 0.3048)
			(end 0.67945 -0.305054)
			(stroke
				(width 0.1)
				(type default)
			)
			(layer "B.Fab")
		)
		(fp_line
			(start 0.12065 0.3048)
			(end 0.67945 0.3048)
			(stroke
				(width 0.1)
				(type default)
			)
			(layer "B.Fab")
		)
		(fp_line
			(start -0.120396 0.3048)
			(end -0.120396 0.2794)
			(stroke
				(width 0.1)
				(type default)
			)
			(layer "B.Fab")
		)
		(fp_line
			(start -0.67945 0.3048)
			(end -0.120396 0.3048)
			(stroke
				(width 0.1)
				(type default)
			)
			(layer "B.Fab")
		)
		(pad "1" smd circle
			(at 0.40005 0 270)
			(size 0 0)
			(layers "B.Cu" "B.Mask" "B.Paste")
			(net "SMB_HOST_3V3AUX_SCL")
		)
		(pad "2" smd circle
			(at -0.40005 0 270)
			(size 0 0)
			(layers "B.Cu" "B.Mask" "B.Paste")
			(net "SMB_HOST_3V3AUX_SCL_R0")
		)
	)
	(footprint ""
		(layer "B.Cu")
		(at 82.462624 -184.096152 90)
		(property "Reference" "R337"
			(at 0 0 90)
			(layer "B.SilkS")
			(hide yes)
			(effects
				(font
					(size 1.27 1.27)
				)
				(justify mirror)
			)
		)
		(property "Value" ""
			(at 0 0 90)
			(layer "B.Fab")
			(effects
				(font
					(size 1.27 1.27)
				)
				(justify mirror)
			)
		)
		(duplicate_pad_numbers_are_jumpers no)
		(fp_line
			(start 0.7874 -0.4064)
			(end -0.7874 -0.4064)
			(stroke
				(width 0.1524)
				(type default)
			)
			(layer "B.SilkS")
		)
		(fp_line
			(start -0.7874 -0.4064)
			(end -0.7874 0.4064)
			(stroke
				(width 0.1524)
				(type default)
			)
			(layer "B.SilkS")
		)
		(fp_line
			(start 0.7874 0.4064)
			(end 0.7874 -0.4064)
			(stroke
				(width 0.1524)
				(type default)
			)
			(layer "B.SilkS")
		)
		(fp_line
			(start -0.7874 0.4064)
			(end 0.7874 0.4064)
			(stroke
				(width 0.1524)
				(type default)
			)
			(layer "B.SilkS")
		)
		(fp_line
			(start 0.67945 -0.305054)
			(end 0.12065 -0.305054)
			(stroke
				(width 0.1)
				(type default)
			)
			(layer "B.Fab")
		)
		(fp_line
			(start 0.12065 -0.305054)
			(end 0.12065 -0.2794)
			(stroke
				(width 0.1)
				(type default)
			)
			(layer "B.Fab")
		)
		(fp_line
			(start -0.12065 -0.3048)
			(end -0.67945 -0.3048)
			(stroke
				(width 0.1)
				(type default)
			)
			(layer "B.Fab")
		)
		(fp_line
			(start -0.67945 -0.3048)
			(end -0.67945 0.3048)
			(stroke
				(width 0.1)
				(type default)
			)
			(layer "B.Fab")
		)
		(fp_line
			(start 0.12065 -0.2794)
			(end -0.12065 -0.2794)
			(stroke
				(width 0.1)
				(type default)
			)
			(layer "B.Fab")
		)
		(fp_line
			(start -0.12065 -0.2794)
			(end -0.12065 -0.3048)
			(stroke
				(width 0.1)
				(type default)
			)
			(layer "B.Fab")
		)
		(fp_line
			(start 0.12065 0.2794)
			(end 0.12065 0.3048)
			(stroke
				(width 0.1)
				(type default)
			)
			(layer "B.Fab")
		)
		(fp_line
			(start -0.120396 0.2794)
			(end 0.12065 0.2794)
			(stroke
				(width 0.1)
				(type default)
			)
			(layer "B.Fab")
		)
		(fp_line
			(start 0.67945 0.3048)
			(end 0.67945 -0.305054)
			(stroke
				(width 0.1)
				(type default)
			)
			(layer "B.Fab")
		)
		(fp_line
			(start 0.12065 0.3048)
			(end 0.67945 0.3048)
			(stroke
				(width 0.1)
				(type default)
			)
			(layer "B.Fab")
		)
		(fp_line
			(start -0.120396 0.3048)
			(end -0.120396 0.2794)
			(stroke
				(width 0.1)
				(type default)
			)
			(layer "B.Fab")
		)
		(fp_line
			(start -0.67945 0.3048)
			(end -0.120396 0.3048)
			(stroke
				(width 0.1)
				(type default)
			)
			(layer "B.Fab")
		)
		(pad "1" smd circle
			(at 0.40005 0 270)
			(size 0 0)
			(layers "B.Cu" "B.Mask" "B.Paste")
			(net "H_CPU1_ERR0_LVC1_R_N")
		)
		(pad "2" smd circle
			(at -0.40005 0 270)
			(size 0 0)
			(layers "B.Cu" "B.Mask" "B.Paste")
			(net "H_CPU_ERR0_LVC1_R_N")
		)
	)
)
